(kicad_pcb
	(version 20260206)
	(generator "pcbnew")
	(generator_version "10.0")
	(general
		(thickness 1.6)
		(legacy_teardrops no)
	)
	(paper "A4")
	(title_block
		(title "Bryce Canyon_F.DPB_16315-1-OCP.brd")
		(comment 1 "Bryce Canyon / footprints 1246-1252 of 2223")
	)
	(layers
		(0 "F.Cu" signal "TOP")
		(4 "In1.Cu" signal "L2GND")
		(6 "In2.Cu" signal "L3")
		(8 "In3.Cu" signal "L4GND")
		(10 "In4.Cu" signal "L5")
		(12 "In5.Cu" signal "L6VCC")
		(14 "In6.Cu" signal "L7VCC")
		(16 "In7.Cu" signal "L8")
		(18 "In8.Cu" signal "L9GND")
		(20 "In9.Cu" signal "L10")
		(22 "In10.Cu" signal "L11GND")
		(2 "B.Cu" signal "BOTTOM")
		(9 "F.Adhes" user "F.Adhesive")
		(11 "B.Adhes" user "B.Adhesive")
		(13 "F.Paste" user "Package Geometry/Pastemask Top")
		(15 "B.Paste" user "Package Geometry/Pastemask Bottom")
		(5 "F.SilkS" user "Ref Des/Silkscreen Top")
		(7 "B.SilkS" user "Ref Des/Silkscreen Bottom")
		(1 "F.Mask" user "Board Geometry/Soldermask Top")
		(3 "B.Mask" user "Board Geometry/Soldermask Bottom")
		(17 "Dwgs.User" user "User.Drawings")
		(19 "Cmts.User" user "User.Comments")
		(21 "Eco1.User" user "User.Eco1")
		(23 "Eco2.User" user "User.Eco2")
		(25 "Edge.Cuts" user "Board Geometry/Outline")
		(27 "Margin" user)
		(31 "F.CrtYd" user "Package Geometry/Place Bound Top")
		(29 "B.CrtYd" user "Package Geometry/Place Bound Bottom")
		(35 "F.Fab" user "Ref Des/Assembly Top")
		(33 "B.Fab" user "Ref Des/Assembly Bottom")
	)
	(footprint ""
		(layer "F.Cu")
		(at 221.681802 -207.983074 -90)
		(property "Reference" "C128"
			(at 0 0 270)
			(layer "F.SilkS")
			(hide yes)
			(effects
				(font
					(size 1.27 1.27)
				)
			)
		)
		(property "Value" "SCD1U16V2KX-3GP"
			(at 1.1811 -2.7051 270)
			(unlocked yes)
			(layer "F.Fab")
			(hide yes)
			(effects
				(font
					(size 1.016 1.016)
					(thickness 0.1524)
				)
			)
		)
		(property "Device Type" "C402H22"
			(at 1.1811 -4.2291 270)
			(unlocked yes)
			(layer "F.Fab")
			(hide yes)
			(effects
				(font
					(size 1.016 1.016)
					(thickness 0.1524)
				)
			)
		)
		(duplicate_pad_numbers_are_jumpers no)
		(fp_rect
			(start -0.4318 0.9525)
			(end 0.4318 -0.9525)
			(stroke
				(width 0)
				(type default)
			)
			(fill no)
			(layer "F.CrtYd")
		)
		(fp_rect
			(start -0.4318 0.9525)
			(end 0.4318 -0.9525)
			(stroke
				(width 0)
				(type default)
			)
			(fill no)
			(layer "F.Fab")
		)
		(pad "1" smd custom
			(at 0 -0.4445 270)
			(size 0.1524 0.1524)
			(layers "F.Cu" "F.Mask" "F.Paste")
			(net "I2C_SCC_BUFF_EN")
			(options
				(clearance outline)
				(anchor circle)
			)
			(primitives
				(gr_poly
					(pts
						(arc
							(start 0.3048 -0.2032)
							(mid 0.275042 -0.275042)
							(end 0.2032 -0.3048)
						)
						(arc
							(start -0.2032 -0.3048)
							(mid -0.275042 -0.275042)
							(end -0.3048 -0.2032)
						)
						(arc
							(start -0.3048 0.2032)
							(mid -0.275042 0.275042)
							(end -0.2032 0.3048)
						)
						(arc
							(start 0.2032 0.3048)
							(mid 0.275042 0.275042)
							(end 0.3048 0.2032)
						)
					)
					(width 0)
					(fill yes)
				)
			)
		)
		(pad "2" smd custom
			(at 0 0.4445 270)
			(size 0.1524 0.1524)
			(layers "F.Cu" "F.Mask" "F.Paste")
			(net "GND")
			(options
				(clearance outline)
				(anchor circle)
			)
			(primitives
				(gr_poly
					(pts
						(arc
							(start 0.3048 -0.2032)
							(mid 0.275042 -0.275042)
							(end 0.2032 -0.3048)
						)
						(arc
							(start -0.2032 -0.3048)
							(mid -0.275042 -0.275042)
							(end -0.3048 -0.2032)
						)
						(arc
							(start -0.3048 0.2032)
							(mid -0.275042 0.275042)
							(end -0.2032 0.3048)
						)
						(arc
							(start 0.2032 0.3048)
							(mid 0.275042 0.275042)
							(end 0.3048 0.2032)
						)
					)
					(width 0)
					(fill yes)
				)
			)
		)
	)
	(footprint ""
		(layer "F.Cu")
		(at 35.654488 -187.508896)
		(property "Reference" "R457"
			(at 0 0 0)
			(layer "F.SilkS")
			(hide yes)
			(effects
				(font
					(size 1.27 1.27)
				)
			)
		)
		(property "Value" "4K7R2J-2-GP"
			(at 0.064008 -3.993896 0)
			(unlocked yes)
			(layer "F.Fab")
			(hide yes)
			(effects
				(font
					(size 1.016 1.016)
					(thickness 0.1524)
				)
			)
		)
		(property "Device Type" "R402H16"
			(at 0.064008 -5.517896 0)
			(unlocked yes)
			(layer "F.Fab")
			(hide yes)
			(effects
				(font
					(size 1.016 1.016)
					(thickness 0.1524)
				)
			)
		)
		(duplicate_pad_numbers_are_jumpers no)
		(fp_line
			(start -0.508 -0.9398)
			(end -0.508 0.9398)
			(stroke
				(width 0.1524)
				(type default)
			)
			(layer "F.SilkS")
		)
		(fp_line
			(start 0.508 -0.9398)
			(end -0.508 -0.9398)
			(stroke
				(width 0.1524)
				(type default)
			)
			(layer "F.SilkS")
		)
		(fp_rect
			(start -0.508 0.9398)
			(end 0.508 -0.9398)
			(stroke
				(width 0)
				(type default)
			)
			(fill no)
			(layer "F.CrtYd")
		)
		(fp_rect
			(start -0.508 0.9398)
			(end 0.508 -0.9398)
			(stroke
				(width 0)
				(type default)
			)
			(fill no)
			(layer "F.Fab")
		)
		(pad "1" smd custom
			(at 0 -0.4445)
			(size 0.1397 0.1397)
			(layers "F.Cu" "F.Mask" "F.Paste")
			(net "DRIVE_A_1_FLT_LED")
			(options
				(clearance outline)
				(anchor circle)
			)
			(primitives
				(gr_poly
					(pts
						(arc
							(start -0.1778 -0.2794)
							(mid -0.249642 -0.249642)
							(end -0.2794 -0.1778)
						)
						(arc
							(start -0.2794 0.1778)
							(mid -0.249642 0.249642)
							(end -0.1778 0.2794)
						)
						(arc
							(start 0.1778 0.2794)
							(mid 0.249642 0.249642)
							(end 0.2794 0.1778)
						)
						(arc
							(start 0.2794 -0.1778)
							(mid 0.249642 -0.249642)
							(end 0.1778 -0.2794)
						)
					)
					(width 0)
					(fill yes)
				)
			)
		)
		(pad "2" smd custom
			(at 0 0.4445)
			(size 0.1397 0.1397)
			(layers "F.Cu" "F.Mask" "F.Paste")
			(net "GND")
			(options
				(clearance outline)
				(anchor circle)
			)
			(primitives
				(gr_poly
					(pts
						(arc
							(start -0.1778 -0.2794)
							(mid -0.249642 -0.249642)
							(end -0.2794 -0.1778)
						)
						(arc
							(start -0.2794 0.1778)
							(mid -0.249642 0.249642)
							(end -0.1778 0.2794)
						)
						(arc
							(start 0.1778 0.2794)
							(mid 0.249642 0.249642)
							(end 0.2794 0.1778)
						)
						(arc
							(start 0.2794 -0.1778)
							(mid 0.249642 -0.249642)
							(end 0.1778 -0.2794)
						)
					)
					(width 0)
					(fill yes)
				)
			)
		)
	)
	(footprint ""
		(layer "F.Cu")
		(at 45.5168 -148.66112 180)
		(property "Reference" "R1242"
			(at 0 0 180)
			(layer "F.SilkS")
			(hide yes)
			(effects
				(font
					(size 1.27 1.27)
				)
			)
		)
		(property "Value" "0R2J-2-GP"
			(at 0.064008 -3.993896 180)
			(unlocked yes)
			(layer "F.Fab")
			(hide yes)
			(effects
				(font
					(size 1.016 1.016)
					(thickness 0.1524)
				)
			)
		)
		(property "Device Type" "R402H16"
			(at 0.064008 -5.517896 180)
			(unlocked yes)
			(layer "F.Fab")
			(hide yes)
			(effects
				(font
					(size 1.016 1.016)
					(thickness 0.1524)
				)
			)
		)
		(duplicate_pad_numbers_are_jumpers no)
		(fp_line
			(start 0.508 -0.9398)
			(end -0.508 -0.9398)
			(stroke
				(width 0.1524)
				(type default)
			)
			(layer "F.SilkS")
		)
		(fp_line
			(start -0.508 -0.9398)
			(end -0.508 0.9398)
			(stroke
				(width 0.1524)
				(type default)
			)
			(layer "F.SilkS")
		)
		(fp_rect
			(start -0.508 0.9398)
			(end 0.508 -0.9398)
			(stroke
				(width 0)
				(type default)
			)
			(fill no)
			(layer "F.CrtYd")
		)
		(fp_rect
			(start -0.508 0.9398)
			(end 0.508 -0.9398)
			(stroke
				(width 0)
				(type default)
			)
			(fill no)
			(layer "F.Fab")
		)
		(pad "1" smd custom
			(at 0 -0.4445 180)
			(size 0.1397 0.1397)
			(layers "F.Cu" "F.Mask" "F.Paste")
			(net "P5V_B_ROVP")
			(options
				(clearance outline)
				(anchor circle)
			)
			(primitives
				(gr_poly
					(pts
						(arc
							(start -0.1778 -0.2794)
							(mid -0.249642 -0.249642)
							(end -0.2794 -0.1778)
						)
						(arc
							(start -0.2794 0.1778)
							(mid -0.249642 0.249642)
							(end -0.1778 0.2794)
						)
						(arc
							(start 0.1778 0.2794)
							(mid 0.249642 0.249642)
							(end 0.2794 0.1778)
						)
						(arc
							(start 0.2794 -0.1778)
							(mid 0.249642 -0.249642)
							(end 0.1778 -0.2794)
						)
					)
					(width 0)
					(fill yes)
				)
			)
		)
		(pad "2" smd custom
			(at 0 0.4445 180)
			(size 0.1397 0.1397)
			(layers "F.Cu" "F.Mask" "F.Paste")
			(net "AGND_P5V_B")
			(options
				(clearance outline)
				(anchor circle)
			)
			(primitives
				(gr_poly
					(pts
						(arc
							(start -0.1778 -0.2794)
							(mid -0.249642 -0.249642)
							(end -0.2794 -0.1778)
						)
						(arc
							(start -0.2794 0.1778)
							(mid -0.249642 0.249642)
							(end -0.1778 0.2794)
						)
						(arc
							(start 0.1778 0.2794)
							(mid 0.249642 0.249642)
							(end 0.2794 0.1778)
						)
						(arc
							(start 0.2794 -0.1778)
							(mid 0.249642 -0.249642)
							(end 0.1778 -0.2794)
						)
					)
					(width 0)
					(fill yes)
				)
			)
		)
	)
	(footprint ""
		(layer "F.Cu")
		(at 301.139352 -74.7903)
		(property "Reference" "R358"
			(at 0 0 0)
			(layer "F.SilkS")
			(hide yes)
			(effects
				(font
					(size 1.27 1.27)
				)
			)
		)
		(property "Value" "0R2J-2-GP"
			(at 0.064008 -3.993896 0)
			(unlocked yes)
			(layer "F.Fab")
			(hide yes)
			(effects
				(font
					(size 1.016 1.016)
					(thickness 0.1524)
				)
			)
		)
		(property "Device Type" "R402H16"
			(at 0.064008 -5.517896 0)
			(unlocked yes)
			(layer "F.Fab")
			(hide yes)
			(effects
				(font
					(size 1.016 1.016)
					(thickness 0.1524)
				)
			)
		)
		(duplicate_pad_numbers_are_jumpers no)
		(fp_line
			(start -0.508 -0.9398)
			(end -0.508 0.9398)
			(stroke
				(width 0.1524)
				(type default)
			)
			(layer "F.SilkS")
		)
		(fp_line
			(start 0.508 -0.9398)
			(end -0.508 -0.9398)
			(stroke
				(width 0.1524)
				(type default)
			)
			(layer "F.SilkS")
		)
		(fp_rect
			(start -0.508 0.9398)
			(end 0.508 -0.9398)
			(stroke
				(width 0)
				(type default)
			)
			(fill no)
			(layer "F.CrtYd")
		)
		(fp_rect
			(start -0.508 0.9398)
			(end 0.508 -0.9398)
			(stroke
				(width 0)
				(type default)
			)
			(fill no)
			(layer "F.Fab")
		)
		(pad "1" smd custom
			(at 0 -0.4445)
			(size 0.1397 0.1397)
			(layers "F.Cu" "F.Mask" "F.Paste")
			(net "SLOT1_SVR_ID0_GPIO1")
			(options
				(clearance outline)
				(anchor circle)
			)
			(primitives
				(gr_poly
					(pts
						(arc
							(start -0.1778 -0.2794)
							(mid -0.249642 -0.249642)
							(end -0.2794 -0.1778)
						)
						(arc
							(start -0.2794 0.1778)
							(mid -0.249642 0.249642)
							(end -0.1778 0.2794)
						)
						(arc
							(start 0.1778 0.2794)
							(mid 0.249642 0.249642)
							(end 0.2794 0.1778)
						)
						(arc
							(start 0.2794 -0.1778)
							(mid 0.249642 -0.249642)
							(end 0.1778 -0.2794)
						)
					)
					(width 0)
					(fill yes)
				)
			)
		)
		(pad "2" smd custom
			(at 0 0.4445)
			(size 0.1397 0.1397)
			(layers "F.Cu" "F.Mask" "F.Paste")
			(net "COMP_B_BMC_B_SPARE_1")
			(options
				(clearance outline)
				(anchor circle)
			)
			(primitives
				(gr_poly
					(pts
						(arc
							(start -0.1778 -0.2794)
							(mid -0.249642 -0.249642)
							(end -0.2794 -0.1778)
						)
						(arc
							(start -0.2794 0.1778)
							(mid -0.249642 0.249642)
							(end -0.1778 0.2794)
						)
						(arc
							(start 0.1778 0.2794)
							(mid 0.249642 0.249642)
							(end 0.2794 0.1778)
						)
						(arc
							(start 0.2794 -0.1778)
							(mid 0.249642 -0.249642)
							(end 0.1778 -0.2794)
						)
					)
					(width 0)
					(fill yes)
				)
			)
		)
	)
	(footprint ""
		(layer "F.Cu")
		(at 370.3828 -133.6294 90)
		(property "Reference" "R1094"
			(at 0 0 90)
			(layer "F.SilkS")
			(hide yes)
			(effects
				(font
					(size 1.27 1.27)
				)
			)
		)
		(property "Value" "100KR2F-L1-GP"
			(at 0.064008 -3.993896 90)
			(unlocked yes)
			(layer "F.Fab")
			(hide yes)
			(effects
				(font
					(size 1.016 1.016)
					(thickness 0.1524)
				)
			)
		)
		(property "Device Type" "R402H16"
			(at 0.064008 -5.517896 90)
			(unlocked yes)
			(layer "F.Fab")
			(hide yes)
			(effects
				(font
					(size 1.016 1.016)
					(thickness 0.1524)
				)
			)
		)
		(duplicate_pad_numbers_are_jumpers no)
		(fp_line
			(start 0.508 -0.9398)
			(end -0.508 -0.9398)
			(stroke
				(width 0.1524)
				(type default)
			)
			(layer "F.SilkS")
		)
		(fp_line
			(start -0.508 -0.9398)
			(end -0.508 0.9398)
			(stroke
				(width 0.1524)
				(type default)
			)
			(layer "F.SilkS")
		)
		(fp_rect
			(start -0.508 0.9398)
			(end 0.508 -0.9398)
			(stroke
				(width 0)
				(type default)
			)
			(fill no)
			(layer "F.CrtYd")
		)
		(fp_rect
			(start -0.508 0.9398)
			(end 0.508 -0.9398)
			(stroke
				(width 0)
				(type default)
			)
			(fill no)
			(layer "F.Fab")
		)
		(pad "1" smd custom
			(at 0 -0.4445 90)
			(size 0.1397 0.1397)
			(layers "F.Cu" "F.Mask" "F.Paste")
			(net "MB1_VCAP_R")
			(options
				(clearance outline)
				(anchor circle)
			)
			(primitives
				(gr_poly
					(pts
						(arc
							(start -0.1778 -0.2794)
							(mid -0.249642 -0.249642)
							(end -0.2794 -0.1778)
						)
						(arc
							(start -0.2794 0.1778)
							(mid -0.249642 0.249642)
							(end -0.1778 0.2794)
						)
						(arc
							(start 0.1778 0.2794)
							(mid 0.249642 0.249642)
							(end 0.2794 0.1778)
						)
						(arc
							(start 0.2794 -0.1778)
							(mid 0.249642 -0.249642)
							(end 0.1778 -0.2794)
						)
					)
					(width 0)
					(fill yes)
				)
			)
		)
		(pad "2" smd custom
			(at 0 0.4445 90)
			(size 0.1397 0.1397)
			(layers "F.Cu" "F.Mask" "F.Paste")
			(net "MB1_ISTART_R")
			(options
				(clearance outline)
				(anchor circle)
			)
			(primitives
				(gr_poly
					(pts
						(arc
							(start -0.1778 -0.2794)
							(mid -0.249642 -0.249642)
							(end -0.2794 -0.1778)
						)
						(arc
							(start -0.2794 0.1778)
							(mid -0.249642 0.249642)
							(end -0.1778 0.2794)
						)
						(arc
							(start 0.1778 0.2794)
							(mid 0.249642 0.249642)
							(end 0.2794 0.1778)
						)
						(arc
							(start 0.2794 -0.1778)
							(mid 0.249642 -0.249642)
							(end 0.1778 -0.2794)
						)
					)
					(width 0)
					(fill yes)
				)
			)
		)
	)
	(footprint ""
		(layer "F.Cu")
		(at 330.67498 -322.799964)
		(property "Reference" ""
			(at 0 0 0)
			(layer "F.SilkS")
			(hide yes)
			(effects
				(font
					(size 1.27 1.27)
				)
			)
		)
		(property "Value" "*"
			(at -8.398764 -8.057642 0)
			(unlocked yes)
			(layer "F.Fab")
			(hide yes)
			(effects
				(font
					(size 1.016 1.016)
					(thickness 0.1524)
				)
			)
		)
		(duplicate_pad_numbers_are_jumpers no)
		(fp_poly
			(pts
				(arc
					(start 7.3152 0)
					(mid 0 7.3152)
					(end -7.3152 0)
				)
				(arc
					(start -7.3152 -5.9944)
					(mid 0 -13.3096)
					(end 7.3152 -5.9944)
				)
			)
			(stroke
				(width 0)
				(type default)
			)
			(fill no)
			(layer "B.CrtYd")
		)
		(fp_poly
			(pts
				(arc
					(start 7.3152 0)
					(mid 0 7.3152)
					(end -7.3152 0)
				)
				(arc
					(start -7.3152 -5.9944)
					(mid 0 -13.3096)
					(end 7.3152 -5.9944)
				)
			)
			(stroke
				(width 0)
				(type default)
			)
			(fill no)
			(layer "F.CrtYd")
		)
		(fp_poly
			(pts
				(arc
					(start 7.3152 0)
					(mid 0 7.3152)
					(end -7.3152 0)
				)
				(arc
					(start -7.3152 -5.9944)
					(mid 0 -13.3096)
					(end 7.3152 -5.9944)
				)
			)
			(stroke
				(width 0)
				(type default)
			)
			(fill no)
			(layer "B.Fab")
		)
		(fp_poly
			(pts
				(arc
					(start 7.3152 0)
					(mid 0 7.3152)
					(end -7.3152 0)
				)
				(arc
					(start -7.3152 -5.9944)
					(mid 0 -13.3096)
					(end 7.3152 -5.9944)
				)
			)
			(stroke
				(width 0)
				(type default)
			)
			(fill no)
			(layer "F.Fab")
		)
		(pad "1" thru_hole oval
			(at 0 0)
			(size 14.0208 20.0152)
			(drill 0.0254
				(offset 0 -2.9972)
			)
			(layers "*.Cu" "*.Mask")
			(remove_unused_layers no)
			(net "Net_97")
			(clearance -1.002284)
			(thermal_gap 0.1524)
			(padstack
				(mode front_inner_back)
				(layer "Inner"
					(shape custom)
					(size 2.928012 2.928012)
					(options
						(anchor circle)
					)
					(primitives
						(gr_poly
							(pts
								(arc
									(start 4.571746 -2.084324)
									(mid 0.000333 7.430372)
									(end -4.571492 -2.084324)
								)
								(arc
									(start -4.571492 -2.084324)
									(mid -3.570296 -3.611977)
									(end -2.875026 -5.30098)
								)
								(arc
									(start -2.875026 -5.30098)
									(mid 0.000217 -7.43089)
									(end 2.87528 -5.30098)
								)
								(arc
									(start 2.87528 -5.30098)
									(mid 3.570511 -3.611956)
									(end 4.571746 -2.084324)
								)
							)
							(width 0)
							(fill yes)
						)
					)
					(clearance 0.1524)
				)
				(layer "B.Cu"
					(shape oval)
					(size 14.0208 20.0152)
					(offset 0 -2.9972)
					(clearance -1.002284)
				)
			)
		)
		(zone
			(layers "F.Cu" "B.Cu" "In1.Cu" "In2.Cu" "In3.Cu" "In4.Cu" "In5.Cu" "In6.Cu"
				"In7.Cu" "In8.Cu" "In9.Cu" "In10.Cu"
			)
			(hatch none 0.5)
			(connect_pads
				(clearance 0)
			)
			(min_thickness 0.25)
			(keepout
				(tracks not_allowed)
				(vias allowed)
				(pads allowed)
				(copperpour not_allowed)
				(footprints allowed)
			)
			(placement
				(enabled no)
				(sheetname "")
			)
			(fill
				(thermal_gap 0.5)
				(thermal_bridge_width 0.5)
				(island_removal_mode 0)
			)
			(polygon
				(pts
					(arc
						(start 323.66458 -328.794364)
						(mid 330.67498 -335.804764)
						(end 337.68538 -328.794364)
					)
					(arc
						(start 337.68538 -322.799964)
						(mid 330.67498 -315.789564)
						(end 323.66458 -322.799964)
					)
				)
			)
		)
	)
	(footprint ""
		(layer "F.Cu")
		(at 416.284664 -43.660568 -90)
		(property "Reference" "C468"
			(at 0 0 270)
			(layer "F.SilkS")
			(hide yes)
			(effects
				(font
					(size 1.27 1.27)
				)
			)
		)
		(property "Value" "SCD01U16V1KX-GP"
			(at -2.8321 -1.7399 270)
			(unlocked yes)
			(layer "F.Fab")
			(hide yes)
			(effects
				(font
					(size 1.016 1.016)
					(thickness 0.1524)
				)
			)
		)
		(property "Device Type" "C0201H13"
			(at -2.8321 -3.2639 270)
			(unlocked yes)
			(layer "F.Fab")
			(hide yes)
			(effects
				(font
					(size 1.016 1.016)
					(thickness 0.1524)
				)
			)
		)
		(duplicate_pad_numbers_are_jumpers no)
		(fp_rect
			(start -0.2794 0.6477)
			(end 0.2794 -0.6477)
			(stroke
				(width 0)
				(type default)
			)
			(fill no)
			(layer "F.CrtYd")
		)
		(fp_rect
			(start -0.2794 0.6477)
			(end 0.2794 -0.6477)
			(stroke
				(width 0)
				(type default)
			)
			(fill no)
			(layer "F.Fab")
		)
		(pad "1" smd custom
			(at 0 -0.2794 270)
			(size 0.0762 0.0762)
			(layers "F.Cu" "F.Mask" "F.Paste")
			(net "SAS_HDD_RX_P33")
			(options
				(clearance outline)
				(anchor circle)
			)
			(primitives
				(gr_poly
					(pts
						(arc
							(start 0.1524 -0.127)
							(mid 0.137521 -0.162921)
							(end 0.1016 -0.1778)
						)
						(arc
							(start -0.1016 -0.1778)
							(mid -0.137521 -0.162921)
							(end -0.1524 -0.127)
						)
						(arc
							(start -0.1524 0.127)
							(mid -0.137521 0.162921)
							(end -0.1016 0.1778)
						)
						(arc
							(start 0.1016 0.1778)
							(mid 0.137521 0.162921)
							(end 0.1524 0.127)
						)
					)
					(width 0)
					(fill yes)
				)
			)
		)
		(pad "2" smd custom
			(at 0 0.2794 270)
			(size 0.0762 0.0762)
			(layers "F.Cu" "F.Mask" "F.Paste")
			(net "PHY_SCC_A_TO_DRV_A_33_DP")
			(options
				(clearance outline)
				(anchor circle)
			)
			(primitives
				(gr_poly
					(pts
						(arc
							(start 0.1524 -0.127)
							(mid 0.137521 -0.162921)
							(end 0.1016 -0.1778)
						)
						(arc
							(start -0.1016 -0.1778)
							(mid -0.137521 -0.162921)
							(end -0.1524 -0.127)
						)
						(arc
							(start -0.1524 0.127)
							(mid -0.137521 0.162921)
							(end -0.1016 0.1778)
						)
						(arc
							(start 0.1016 0.1778)
							(mid 0.137521 0.162921)
							(end 0.1524 0.127)
						)
					)
					(width 0)
					(fill yes)
				)
			)
		)
	)
)
